# S9S_MB_2U (Grand Teton) — schematic netlist excerpt (pin names and nets, part order shuffled) for the footprints in the layout excerpt that follows; sources: Cadence DE-HDL packaged netlist, KiCad conversion of 03242023_DA0F0TMBIJ0_F0T_Motherboard_J_brd_V01_OCP.brd

J112  CONN160_10131762101LF  CONN160_10131762-101LF IO  pkg HSD_F160D8_P2W1-2_RDH  page 143
  A1  = RST_PERST_2_SWB_BUF_N
  A2  = GND
  A3  = HGX_DETECT_N_ISO
  A4  = GND
  A5  = RST_PERST_1_SWB_BUF_N
  A6  = GND
  A7  = PRSNT_SWB_N
  A8  = GND
  B1  = GND
  B2  = P5E_CPU1_PE0_RX_DN<14>
  B3  = GND
  B4  = P5E_CPU1_PE0_RX_DN<12>
  B5  = GND
  B6  = P5E_CPU1_PE0_RX_DN<10>
  B7  = GND
  B8  = P5E_CPU1_PE0_RX_DN<8>
  C1  = P5E_CPU1_PE0_RX_DN<15>
  C2  = P5E_CPU1_PE0_RX_DP<14>
  C3  = P5E_CPU1_PE0_RX_DN<13>
  C4  = P5E_CPU1_PE0_RX_DP<12>
  C5  = P5E_CPU1_PE0_RX_DP<11>
  C6  = P5E_CPU1_PE0_RX_DP<10>
  C7  = P5E_CPU1_PE0_RX_DN<9>
  C8  = P5E_CPU1_PE0_RX_DP<8>
  D1  = P5E_CPU1_PE0_RX_DP<15>
  D2  = GND
  D3  = P5E_CPU1_PE0_RX_DP<13>
  D4  = GND
  D5  = P5E_CPU1_PE0_RX_DN<11>
  D6  = GND
  D7  = P5E_CPU1_PE0_RX_DP<9>
  D8  = GND
  E1  = GND
  E2  = P5E_CPU1_PE4_RX_DP<1>
  E3  = GND
  E4  = P5E_CPU1_PE4_RX_DP<3>
  E5  = GND
  E6  = P5E_CPU1_PE4_RX_DP<5>
  E7  = GND
  E8  = P5E_CPU1_PE4_RX_DP<7>
  F1  = P5E_CPU1_PE4_RX_DN<0>
  F2  = P5E_CPU1_PE4_RX_DN<1>
  F3  = P5E_CPU1_PE4_RX_DN<2>
  F4  = P5E_CPU1_PE4_RX_DN<3>
  F5  = P5E_CPU1_PE4_RX_DN<4>
  F6  = P5E_CPU1_PE4_RX_DN<5>
  F7  = P5E_CPU1_PE4_RX_DN<6>
  F8  = P5E_CPU1_PE4_RX_DN<7>
  G1  = P5E_CPU1_PE4_RX_DP<0>
  G2  = GND
  G3  = P5E_CPU1_PE4_RX_DP<2>
  G4  = GND
  G5  = P5E_CPU1_PE4_RX_DP<4>
  G6  = GND
  G7  = P5E_CPU1_PE4_RX_DP<6>
  G8  = GND
  H1  = GND
  H2  = P5E_CPU1_PE0_TX_C_DN<14>
  H3  = GND
  H4  = P5E_CPU1_PE0_TX_C_DN<12>
  H5  = GND
  H6  = P5E_CPU1_PE0_TX_C_DN<10>
  H7  = GND
  H8  = P5E_CPU1_PE0_TX_C_DN<8>
  I1  = P5E_CPU1_PE0_TX_C_DN<15>
  I2  = P5E_CPU1_PE0_TX_C_DP<14>
  I3  = P5E_CPU1_PE0_TX_C_DN<13>
  I4  = P5E_CPU1_PE0_TX_C_DP<12>
  I5  = P5E_CPU1_PE0_TX_C_DN<11>
  I6  = P5E_CPU1_PE0_TX_C_DP<10>
  I7  = P5E_CPU1_PE0_TX_C_DN<9>
  I8  = P5E_CPU1_PE0_TX_C_DP<8>
  J1  = P5E_CPU1_PE0_TX_C_DP<15>
  J2  = GND
  J3  = P5E_CPU1_PE0_TX_C_DP<13>
  J4  = GND
  J5  = P5E_CPU1_PE0_TX_C_DP<11>
  J6  = GND
  J7  = P5E_CPU1_PE0_TX_C_DP<9>
  J8  = GND
  K1  = GND
  K2  = P5E_CPU1_PE4_TX_C_DP<1>
  K3  = GND
  K4  = P5E_CPU1_PE4_TX_C_DN<3>
  K5  = GND
  K6  = P5E_CPU1_PE4_TX_C_DN<5>
  K7  = GND
  K8  = P5E_CPU1_PE4_TX_C_DN<7>
  L1  = P5E_CPU1_PE4_TX_C_DN<0>
  L2  = P5E_CPU1_PE4_TX_C_DN<1>
  L3  = P5E_CPU1_PE4_TX_C_DN<2>
  L4  = P5E_CPU1_PE4_TX_C_DP<3>
  L5  = P5E_CPU1_PE4_TX_C_DN<4>
  L6  = P5E_CPU1_PE4_TX_C_DP<5>
  L7  = P5E_CPU1_PE4_TX_C_DN<6>
  L8  = P5E_CPU1_PE4_TX_C_DP<7>
  M1  = P5E_CPU1_PE4_TX_C_DP<0>
  M2  = GND
  M3  = P5E_CPU1_PE4_TX_C_DP<2>
  M4  = GND
  M5  = P5E_CPU1_PE4_TX_C_DP<4>
  M6  = GND
  M7  = P5E_CPU1_PE4_TX_C_DP<6>
  M8  = GND
  N1  = GND
  N2  = NC_J112_N2
  N3  = GND
  N4  = CLK_100M_GPU_1_DN
  N5  = GND
  N6  = P2E_MB_BMC_RX_DN<0>
  N7  = GND
  N8  = P3E_PCH_NVS_RX_DN<0>
  O1  = CLK_100M_GPU_2_DN
  O2  = NC_J112_O2
  O3  = CLK_100M_SWB_DN
  O4  = CLK_100M_GPU_1_DP
  O5  = NC_J112_O5
  O6  = P2E_MB_BMC_RX_DP<0>
  O7  = P3E_PCH_NVS_RX_DN<1>
  O8  = P3E_PCH_NVS_RX_DP<0>
  P1  = CLK_100M_GPU_2_DP
  P2  = GND
  P3  = CLK_100M_SWB_DP
  P4  = GND
  P5  = NC_J112_P5
  P6  = GND
  P7  = P3E_PCH_NVS_RX_DP<1>
  P8  = GND
  Q1  = GND
  Q2  = CLK_100M_GPU_FPGA_DN
  Q3  = GND
  Q4  = SMB_1_BMC_GPU_BUF_SCL
  Q5  = GND
  Q6  = P2E_MB_BMC_TX_BUF_C_DN<0>
  Q7  = GND
  Q8  = P3E_PCH_NVS_TX_C_DN<0>
  R1  = USB2_HUB_BUF_SWB_DN
  R2  = CLK_100M_GPU_FPGA_DP
  R3  = SMB_2_BMC_GPU_BUF_SCL
  R4  = SMB_1_BMC_GPU_BUF_SDA
  R5  = NC_J112_R5
  R6  = P2E_MB_BMC_TX_BUF_C_DP<0>
  R7  = P3E_PCH_NVS_TX_C_DN<1>
  R8  = P3E_PCH_NVS_TX_C_DP<0>
  S1  = USB2_HUB_BUF_SWB_DP
  S2  = GND
  S3  = SMB_2_BMC_GPU_BUF_SDA
  S4  = GND
  S5  = NC_J112_S5
  S6  = GND
  S7  = P3E_PCH_NVS_TX_C_DP<1>
  S8  = GND
  T1  = GND
  T2  = GPU_FPGA_READY
  T3  = GND
  T4  = GPU_NVS_PWR_BRAKE_N_BUF
  T5  = GND
  T6  = GPU_FPGA_THERM_OVERT_N
  T7  = GND
  T8  = RST_PERST_0_SWB_BUF_N

(kicad_pcb
	(version 20260206)
	(generator "pcbnew")
	(generator_version "10.0")
	(general
		(thickness 1.6)
		(legacy_teardrops no)
	)
	(paper "A4")
	(title_block
		(title "03242023_DA0F0TMBIJ0_F0T_Motherboard_J_brd_V01_OCP.brd")
		(comment 1 "Grand Teton / footprint 2126 of 6105 (J112), pads 63-90 of 90")
	)
	(layers
		(0 "F.Cu" signal "TOP")
		(4 "In1.Cu" signal "GND")
		(6 "In2.Cu" signal "IN1")
		(8 "In3.Cu" signal "GND1")
		(10 "In4.Cu" signal "IN2")
		(12 "In5.Cu" signal "GND2")
		(14 "In6.Cu" signal "IN3")
		(16 "In7.Cu" signal "GND3")
		(18 "In8.Cu" signal "VCC")
		(20 "In9.Cu" signal "VCC1")
		(22 "In10.Cu" signal "GND4")
		(24 "In11.Cu" signal "IN4")
		(26 "In12.Cu" signal "GND5")
		(28 "In13.Cu" signal "IN5")
		(30 "In14.Cu" signal "GND6")
		(32 "In15.Cu" signal "IN6")
		(34 "In16.Cu" signal "GND7")
		(2 "B.Cu" signal "BOTTOM")
		(9 "F.Adhes" user "F.Adhesive")
		(11 "B.Adhes" user "B.Adhesive")
		(13 "F.Paste" user "Package Geometry/Pastemask Top")
		(15 "B.Paste" user "Package Geometry/Pastemask Bottom")
		(5 "F.SilkS" user "Ref Des/Silkscreen Top")
		(7 "B.SilkS" user "Ref Des/Silkscreen Bottom")
		(1 "F.Mask" user "Board Geometry/Soldermask Top")
		(3 "B.Mask" user "Board Geometry/Soldermask Bottom")
		(17 "Dwgs.User" user "User.Drawings")
		(19 "Cmts.User" user "User.Comments")
		(21 "Eco1.User" user "User.Eco1")
		(23 "Eco2.User" user "User.Eco2")
		(25 "Edge.Cuts" user "Board Geometry/Outline")
		(27 "Margin" user)
		(31 "F.CrtYd" user "Package Geometry/Place Bound Top")
		(29 "B.CrtYd" user "Package Geometry/Place Bound Bottom")
		(35 "F.Fab" user "Ref Des/Assembly Top")
		(33 "B.Fab" user "Ref Des/Assembly Bottom")
	)
	(footprint ""
		(layer "F.Cu")
		(at 58.650124 -440.489848)
		(property "Reference" "J112"
			(at -7.9883 9.742932 0)
			(unlocked yes)
			(layer "F.SilkS")
			(effects
				(font
					(size 0.7874 0.5842)
					(thickness 0.1524)
				)
				(justify left)
			)
		)
		(property "Value" ""
			(at 0 0 0)
			(layer "F.Fab")
			(effects
				(font
					(size 1.27 1.27)
				)
			)
		)
		(duplicate_pad_numbers_are_jumpers no)
		(pad "Q1" thru_hole circle
			(at 0 19.200114 180)
			(size 0.906272 0.906272)
			(drill 0.499872)
			(layers "*.Cu" "*.Mask")
			(remove_unused_layers no)
			(net "GND")
			(clearance 0.0508)
			(thermal_gap 0.0508)
		)
		(pad "Q2" thru_hole circle
			(at 1.999996 19.400012 180)
			(size 0.766318 0.766318)
			(drill 0.359918)
			(layers "*.Cu" "*.Mask")
			(remove_unused_layers no)
			(net "CLK_100M_GPU_FPGA_DN")
			(clearance 0.0508)
			(thermal_gap 0.0508)
		)
		(pad "Q3" thru_hole circle
			(at 3.999992 19.200114 180)
			(size 0.906272 0.906272)
			(drill 0.499872)
			(layers "*.Cu" "*.Mask")
			(remove_unused_layers no)
			(net "GND")
			(clearance 0.0508)
			(thermal_gap 0.0508)
		)
		(pad "Q4" thru_hole circle
			(at 5.999988 19.400012 180)
			(size 0.766318 0.766318)
			(drill 0.359918)
			(layers "*.Cu" "*.Mask")
			(remove_unused_layers no)
			(net "SMB_1_BMC_GPU_BUF_SCL")
			(clearance 0.0508)
			(thermal_gap 0.0508)
		)
		(pad "Q5" thru_hole circle
			(at 7.999984 19.200114 180)
			(size 0.906272 0.906272)
			(drill 0.499872)
			(layers "*.Cu" "*.Mask")
			(remove_unused_layers no)
			(net "GND")
			(clearance 0.0508)
			(thermal_gap 0.0508)
		)
		(pad "Q7" thru_hole circle
			(at 11.999976 19.200114 180)
			(size 0.906272 0.906272)
			(drill 0.499872)
			(layers "*.Cu" "*.Mask")
			(remove_unused_layers no)
			(net "GND")
			(clearance 0.0508)
			(thermal_gap 0.0508)
		)
		(pad "R1" thru_hole circle
			(at 0 20.40001 180)
			(size 0.766318 0.766318)
			(drill 0.359918)
			(layers "*.Cu" "*.Mask")
			(remove_unused_layers no)
			(net "USB2_HUB_BUF_SWB_DN")
			(clearance 0.0508)
			(thermal_gap 0.0508)
		)
		(pad "R2" thru_hole circle
			(at 1.999996 20.599908 180)
			(size 0.766318 0.766318)
			(drill 0.359918)
			(layers "*.Cu" "*.Mask")
			(remove_unused_layers no)
			(net "CLK_100M_GPU_FPGA_DP")
			(clearance 0.0508)
			(thermal_gap 0.0508)
		)
		(pad "R3" thru_hole circle
			(at 3.999992 20.40001 180)
			(size 0.766318 0.766318)
			(drill 0.359918)
			(layers "*.Cu" "*.Mask")
			(remove_unused_layers no)
			(net "SMB_2_BMC_GPU_BUF_SCL")
			(clearance 0.0508)
			(thermal_gap 0.0508)
		)
		(pad "R4" thru_hole circle
			(at 5.999988 20.599908 180)
			(size 0.766318 0.766318)
			(drill 0.359918)
			(layers "*.Cu" "*.Mask")
			(remove_unused_layers no)
			(net "SMB_1_BMC_GPU_BUF_SDA")
			(clearance 0.0508)
			(thermal_gap 0.0508)
		)
		(pad "R5" thru_hole circle
			(at 7.999984 20.40001 180)
			(size 0.766318 0.766318)
			(drill 0.359918)
			(layers "*.Cu" "*.Mask")
			(remove_unused_layers no)
			(net "NC_J112_R5")
			(clearance 0.0508)
			(thermal_gap 0.0508)
		)
		(pad "R7" thru_hole circle
			(at 11.999976 20.40001 180)
			(size 0.766318 0.766318)
			(drill 0.359918)
			(layers "*.Cu" "*.Mask")
			(remove_unused_layers no)
			(net "P3E_PCH_NVS_TX_C_DN<1>")
			(clearance 0.0508)
			(thermal_gap 0.0508)
		)
		(pad "S1" thru_hole circle
			(at 0 21.599906 180)
			(size 0.766318 0.766318)
			(drill 0.359918)
			(layers "*.Cu" "*.Mask")
			(remove_unused_layers no)
			(net "USB2_HUB_BUF_SWB_DP")
			(clearance 0.0508)
			(thermal_gap 0.0508)
		)
		(pad "S2" thru_hole circle
			(at 1.999996 21.800058 180)
			(size 0.906272 0.906272)
			(drill 0.499872)
			(layers "*.Cu" "*.Mask")
			(remove_unused_layers no)
			(net "GND")
			(clearance 0.0508)
			(thermal_gap 0.0508)
		)
		(pad "S3" thru_hole circle
			(at 3.999992 21.599906 180)
			(size 0.766318 0.766318)
			(drill 0.359918)
			(layers "*.Cu" "*.Mask")
			(remove_unused_layers no)
			(net "SMB_2_BMC_GPU_BUF_SDA")
			(clearance 0.0508)
			(thermal_gap 0.0508)
		)
		(pad "S4" thru_hole circle
			(at 5.999988 21.800058 180)
			(size 0.906272 0.906272)
			(drill 0.499872)
			(layers "*.Cu" "*.Mask")
			(remove_unused_layers no)
			(net "GND")
			(clearance 0.0508)
			(thermal_gap 0.0508)
		)
		(pad "S5" thru_hole circle
			(at 7.999984 21.599906 180)
			(size 0.766318 0.766318)
			(drill 0.359918)
			(layers "*.Cu" "*.Mask")
			(remove_unused_layers no)
			(net "NC_J112_S5")
			(clearance 0.0508)
			(thermal_gap 0.0508)
		)
		(pad "S6" thru_hole circle
			(at 9.99998 21.800058 180)
			(size 0.906272 0.906272)
			(drill 0.499872)
			(layers "*.Cu" "*.Mask")
			(remove_unused_layers no)
			(net "GND")
			(clearance 0.0508)
			(thermal_gap 0.0508)
		)
		(pad "S7" thru_hole circle
			(at 11.999976 21.599906 180)
			(size 0.766318 0.766318)
			(drill 0.359918)
			(layers "*.Cu" "*.Mask")
			(remove_unused_layers no)
			(net "P3E_PCH_NVS_TX_C_DP<1>")
			(clearance 0.0508)
			(thermal_gap 0.0508)
		)
		(pad "S8" thru_hole circle
			(at 13.999972 21.800058 180)
			(size 0.906272 0.906272)
			(drill 0.499872)
			(layers "*.Cu" "*.Mask")
			(remove_unused_layers no)
			(net "GND")
			(clearance 0.0508)
			(thermal_gap 0.0508)
		)
		(pad "T1" thru_hole circle
			(at 0 22.800056 180)
			(size 0.906272 0.906272)
			(drill 0.499872)
			(layers "*.Cu" "*.Mask")
			(remove_unused_layers no)
			(net "GND")
			(clearance 0.0508)
			(thermal_gap 0.0508)
		)
		(pad "T2" thru_hole circle
			(at 1.999996 22.999954 180)
			(size 0.766318 0.766318)
			(drill 0.359918)
			(layers "*.Cu" "*.Mask")
			(remove_unused_layers no)
			(net "GPU_FPGA_READY")
			(clearance 0.0508)
			(thermal_gap 0.0508)
		)
		(pad "T3" thru_hole circle
			(at 3.999992 22.800056 180)
			(size 0.906272 0.906272)
			(drill 0.499872)
			(layers "*.Cu" "*.Mask")
			(remove_unused_layers no)
			(net "GND")
			(clearance 0.0508)
			(thermal_gap 0.0508)
		)
		(pad "T4" thru_hole circle
			(at 5.999988 22.999954 180)
			(size 0.766318 0.766318)
			(drill 0.359918)
			(layers "*.Cu" "*.Mask")
			(remove_unused_layers no)
			(net "GPU_NVS_PWR_BRAKE_N_BUF")
			(clearance 0.0508)
			(thermal_gap 0.0508)
		)
		(pad "T5" thru_hole circle
			(at 7.999984 22.800056 180)
			(size 0.906272 0.906272)
			(drill 0.499872)
			(layers "*.Cu" "*.Mask")
			(remove_unused_layers no)
			(net "GND")
			(clearance 0.0508)
			(thermal_gap 0.0508)
		)
		(pad "T6" thru_hole circle
			(at 9.99998 22.999954 180)
			(size 0.766318 0.766318)
			(drill 0.359918)
			(layers "*.Cu" "*.Mask")
			(remove_unused_layers no)
			(net "GPU_FPGA_THERM_OVERT_N")
			(clearance 0.0508)
			(thermal_gap 0.0508)
		)
		(pad "T7" thru_hole circle
			(at 11.999976 22.800056 180)
			(size 0.906272 0.906272)
			(drill 0.499872)
			(layers "*.Cu" "*.Mask")
			(remove_unused_layers no)
			(net "GND")
			(clearance 0.0508)
			(thermal_gap 0.0508)
		)
		(pad "T8" thru_hole circle
			(at 13.999972 22.999954 180)
			(size 0.766318 0.766318)
			(drill 0.359918)
			(layers "*.Cu" "*.Mask")
			(remove_unused_layers no)
			(net "RST_PERST_0_SWB_BUF_N")
			(clearance 0.0508)
			(thermal_gap 0.0508)
		)
	)
)
